FILE_TYPE = CONNECTIVITY;
{Allegro Design Entry HDL 16.6-p007 (v16-6-112F) 10/10/2012}
"PAGE_NUMBER" = 129;
0"NC";
1"DMI_CPU0_PCH_RX_DN<3:0>";
2"DMI_CPU0_PCH_TX_DN<3:0>";
3"DMI_CPU0_PCH_TX_DP<3:0>";
4"DMI_CPU0_PCH_RX_DP<3:0>";
5"DMI_CPU0_PCH_TX_C_DN<3:0>";
6"DMI_CPU0_PCH_RX_C_DN<3:0>";
7"DMI_CPU0_PCH_TX_C_DP<3:0>";
8"DMI_CPU0_PCH_RX_C_DP<3:0>";
9"DMI_CPU0_PCH_TX_DP<3>";
10"DMI_CPU0_PCH_TX_DP<2>";
11"DMI_CPU0_PCH_TX_DP<1>";
12"DMI_CPU0_PCH_RX_DP<0>";
13"DMI_CPU0_PCH_RX_DP<1>";
14"DMI_CPU0_PCH_RX_DP<2>";
15"DMI_CPU0_PCH_RX_DP<3>";
16"DMI_CPU0_PCH_TX_DP<0>";
17"DMI_CPU0_PCH_RX_C_DP<0>";
18"DMI_CPU0_PCH_RX_C_DP<2>";
19"DMI_CPU0_PCH_RX_C_DP<3>";
20"DMI_CPU0_PCH_RX_C_DP<1>";
21"DMI_CPU0_PCH_TX_C_DP<3>";
22"DMI_CPU0_PCH_TX_C_DP<2>";
23"DMI_CPU0_PCH_TX_C_DP<1>";
24"DMI_CPU0_PCH_TX_C_DP<0>";
25"DMI_CPU0_PCH_RX_DN<0>";
26"DMI_CPU0_PCH_TX_DN<0>";
27"DMI_CPU0_PCH_TX_DN<1>";
28"DMI_CPU0_PCH_TX_DN<2>";
29"DMI_CPU0_PCH_TX_DN<3>";
30"DMI_CPU0_PCH_RX_DN<1>";
31"DMI_CPU0_PCH_RX_DN<2>";
32"DMI_CPU0_PCH_RX_DN<3>";
33"DMI_CPU0_PCH_RX_C_DN<0>";
34"DMI_CPU0_PCH_RX_C_DN<1>";
35"DMI_CPU0_PCH_RX_C_DN<2>";
36"DMI_CPU0_PCH_RX_C_DN<3>";
37"DMI_CPU0_PCH_TX_C_DN<0>";
38"DMI_CPU0_PCH_TX_C_DN<1>";
39"DMI_CPU0_PCH_TX_C_DN<2>";
40"DMI_CPU0_PCH_TX_C_DN<3>";
%"TAP"
"6","(1200,3975)","2","mstr_standard","I11";
;
HDL_TAP"TRUE"
BODY_TYPE"PLUMBING"
CDS_LIB"mstr_standard"
BOM_COST"SB";
"B \NAC \NWC"6;
"S \NAC"
BN"3"36;
%"TAP"
"6","(1200,3775)","2","mstr_standard","I12";
;
HDL_TAP"TRUE"
BODY_TYPE"PLUMBING"
CDS_LIB"mstr_standard"
BOM_COST"SB";
"B \NAC \NWC"6;
"S \NAC"
BN"2"35;
%"TAP"
"6","(1200,3375)","2","mstr_standard","I13";
;
HDL_TAP"TRUE"
BODY_TYPE"PLUMBING"
CDS_LIB"mstr_standard"
BOM_COST"SB";
"B \NAC \NWC"6;
"S \NAC"
BN"0"33;
%"TAP"
"6","(1200,3575)","2","mstr_standard","I14";
;
HDL_TAP"TRUE"
BODY_TYPE"PLUMBING"
CDS_LIB"mstr_standard"
BOM_COST"SB";
"B \NAC \NWC"6;
"S \NAC"
BN"1"34;
%"TAP"
"6","(1200,4925)","2","mstr_standard","I2";
;
HDL_TAP"TRUE"
BODY_TYPE"PLUMBING"
CDS_LIB"mstr_standard"
BOM_COST"SB";
"B \NAC \NWC"5;
"S \NAC"
BN"3"40;
%"TAP"
"1","(-125,4925)","2","mstr_standard","I23";
;
HDL_TAP"TRUE"
BODY_TYPE"PLUMBING"
CDS_LIB"mstr_standard"
BOM_COST"SB";
"B \NAC \NWC"2;
"S \NAC"
BN"3"29;
%"TAP"
"1","(-125,4725)","2","mstr_standard","I24";
;
HDL_TAP"TRUE"
BODY_TYPE"PLUMBING"
CDS_LIB"mstr_standard"
BOM_COST"SB";
"B \NAC \NWC"2;
"S \NAC"
BN"2"28;
%"TAP"
"1","(-125,4525)","2","mstr_standard","I25";
;
HDL_TAP"TRUE"
BODY_TYPE"PLUMBING"
CDS_LIB"mstr_standard"
BOM_COST"SB";
"B \NAC \NWC"2;
"S \NAC"
BN"1"27;
%"TAP"
"1","(-125,4325)","2","mstr_standard","I26";
;
HDL_TAP"TRUE"
BODY_TYPE"PLUMBING"
CDS_LIB"mstr_standard"
BOM_COST"SB";
"B \NAC \NWC"2;
"S \NAC"
BN"0"26;
%"TAP"
"6","(-2800,4925)","2","mstr_standard","I29";
;
HDL_TAP"TRUE"
BODY_TYPE"PLUMBING"
CDS_LIB"mstr_standard"
BOM_COST"SB";
"B \NAC \NWC"7;
"S \NAC"
BN"3"21;
%"TAP"
"6","(1200,4725)","2","mstr_standard","I3";
;
HDL_TAP"TRUE"
BODY_TYPE"PLUMBING"
CDS_LIB"mstr_standard"
BOM_COST"SB";
"B \NAC \NWC"5;
"S \NAC"
BN"2"39;
%"TAP"
"6","(-2800,4725)","2","mstr_standard","I30";
;
HDL_TAP"TRUE"
BODY_TYPE"PLUMBING"
CDS_LIB"mstr_standard"
BOM_COST"SB";
"B \NAC \NWC"7;
"S \NAC"
BN"2"22;
%"TAP"
"6","(-2800,4525)","2","mstr_standard","I31";
;
HDL_TAP"TRUE"
BODY_TYPE"PLUMBING"
CDS_LIB"mstr_standard"
BOM_COST"SB";
"B \NAC \NWC"7;
"S \NAC"
BN"1"23;
%"TAP"
"6","(-2800,4325)","2","mstr_standard","I32";
;
HDL_TAP"TRUE"
BODY_TYPE"PLUMBING"
CDS_LIB"mstr_standard"
BOM_COST"SB";
"B \NAC \NWC"7;
"S \NAC"
BN"0"24;
%"CAP"
"1","(-3650,4925)","1","mstr_discrete","I35";
;
ROOM"DMI"
CDS_LOCATION"C7B25"
$SEC"1"
CDS_SEC"1"
CDS_LIB"mstr_discrete"
BOM_COST"SB"
VOLTAGE"16V"
MATERIAL"X7R"
PACK_TYPE"0402"
TOLERANCE"10%"
VALUE"0.22UF"
PART_NUMBER"A36096-155"
LOCATION"C7B25";
"A"
$PN"1"9;
"B"
$PN"2"21;
%"TAP"
"1","(-150,3975)","2","mstr_standard","I37";
;
HDL_TAP"TRUE"
BODY_TYPE"PLUMBING"
CDS_LIB"mstr_standard"
BOM_COST"SB";
"B \NAC \NWC"1;
"S \NAC"
BN"3"32;
%"TAP"
"1","(-150,3775)","2","mstr_standard","I38";
;
HDL_TAP"TRUE"
BODY_TYPE"PLUMBING"
CDS_LIB"mstr_standard"
BOM_COST"SB";
"B \NAC \NWC"1;
"S \NAC"
BN"2"31;
%"TAP"
"1","(-150,3375)","2","mstr_standard","I39";
;
HDL_TAP"TRUE"
BODY_TYPE"PLUMBING"
CDS_LIB"mstr_standard"
BOM_COST"SB";
"B \NAC \NWC"1;
"S \NAC"
BN"0"25;
%"TAP"
"6","(1200,4525)","2","mstr_standard","I4";
;
HDL_TAP"TRUE"
BODY_TYPE"PLUMBING"
CDS_LIB"mstr_standard"
BOM_COST"SB";
"B \NAC \NWC"5;
"S \NAC"
BN"1"38;
%"TAP"
"1","(-150,3575)","2","mstr_standard","I40";
;
HDL_TAP"TRUE"
BODY_TYPE"PLUMBING"
CDS_LIB"mstr_standard"
BOM_COST"SB";
"B \NAC \NWC"1;
"S \NAC"
BN"1"30;
%"TAP"
"6","(-2800,3975)","2","mstr_standard","I45";
;
HDL_TAP"TRUE"
BODY_TYPE"PLUMBING"
CDS_LIB"mstr_standard"
BOM_COST"SB";
"B \NAC \NWC"8;
"S \NAC"
BN"3"19;
%"TAP"
"6","(-2800,3775)","2","mstr_standard","I46";
;
HDL_TAP"TRUE"
BODY_TYPE"PLUMBING"
CDS_LIB"mstr_standard"
BOM_COST"SB";
"B \NAC \NWC"8;
"S \NAC"
BN"2"18;
%"TAP"
"6","(-2800,3375)","2","mstr_standard","I47";
;
HDL_TAP"TRUE"
BODY_TYPE"PLUMBING"
CDS_LIB"mstr_standard"
BOM_COST"SB";
"B \NAC \NWC"8;
"S \NAC"
BN"0"17;
%"TAP"
"6","(-2800,3575)","2","mstr_standard","I48";
;
HDL_TAP"TRUE"
BODY_TYPE"PLUMBING"
CDS_LIB"mstr_standard"
BOM_COST"SB";
"B \NAC \NWC"8;
"S \NAC"
BN"1"20;
%"TAP"
"6","(1200,4325)","2","mstr_standard","I5";
;
HDL_TAP"TRUE"
BODY_TYPE"PLUMBING"
CDS_LIB"mstr_standard"
BOM_COST"SB";
"B \NAC \NWC"5;
"S \NAC"
BN"0"37;
%"TAP"
"1","(-4150,4925)","2","mstr_standard","I57";
;
HDL_TAP"TRUE"
BODY_TYPE"PLUMBING"
CDS_LIB"mstr_standard"
BOM_COST"SB";
"B \NAC \NWC"3;
"S \NAC"
BN"3"9;
%"TAP"
"1","(-4150,4725)","2","mstr_standard","I58";
;
HDL_TAP"TRUE"
BODY_TYPE"PLUMBING"
CDS_LIB"mstr_standard"
BOM_COST"SB";
"B \NAC \NWC"3;
"S \NAC"
BN"2"10;
%"TAP"
"1","(-4150,4525)","2","mstr_standard","I59";
;
HDL_TAP"TRUE"
BODY_TYPE"PLUMBING"
CDS_LIB"mstr_standard"
BOM_COST"SB";
"B \NAC \NWC"3;
"S \NAC"
BN"1"11;
%"TAP"
"1","(-4150,4325)","2","mstr_standard","I60";
;
HDL_TAP"TRUE"
BODY_TYPE"PLUMBING"
CDS_LIB"mstr_standard"
BOM_COST"SB";
"B \NAC \NWC"3;
"S \NAC"
BN"0"16;
%"TAP"
"1","(-4150,3975)","2","mstr_standard","I62";
;
HDL_TAP"TRUE"
BODY_TYPE"PLUMBING"
CDS_LIB"mstr_standard"
BOM_COST"SB";
"B \NAC \NWC"4;
"S \NAC"
BN"3"15;
%"TAP"
"1","(-4150,3775)","2","mstr_standard","I63";
;
HDL_TAP"TRUE"
BODY_TYPE"PLUMBING"
CDS_LIB"mstr_standard"
BOM_COST"SB";
"B \NAC \NWC"4;
"S \NAC"
BN"2"14;
%"TAP"
"1","(-4150,3375)","2","mstr_standard","I64";
;
HDL_TAP"TRUE"
BODY_TYPE"PLUMBING"
CDS_LIB"mstr_standard"
BOM_COST"SB";
"B \NAC \NWC"4;
"S \NAC"
BN"0"12;
%"TAP"
"1","(-4150,3575)","2","mstr_standard","I65";
;
HDL_TAP"TRUE"
BODY_TYPE"PLUMBING"
CDS_LIB"mstr_standard"
BOM_COST"SB";
"B \NAC \NWC"4;
"S \NAC"
BN"1"13;
%"CAP"
"1","(-3300,4725)","1","mstr_discrete","I69";
;
ROOM"DMI"
CDS_LOCATION"C7B27"
$SEC"1"
CDS_SEC"1"
CDS_LIB"mstr_discrete"
BOM_COST"SB"
VOLTAGE"16V"
MATERIAL"X7R"
PACK_TYPE"0402"
TOLERANCE"10%"
VALUE"0.22UF"
PART_NUMBER"A36096-155"
LOCATION"C7B27";
"A"
$PN"1"10;
"B"
$PN"2"22;
%"CAP"
"1","(-3650,4525)","1","mstr_discrete","I70";
;
ROOM"DMI"
CDS_LOCATION"C7B28"
$SEC"1"
CDS_SEC"1"
CDS_LIB"mstr_discrete"
BOM_COST"SB"
VOLTAGE"16V"
MATERIAL"X7R"
PACK_TYPE"0402"
TOLERANCE"10%"
VALUE"0.22UF"
PART_NUMBER"A36096-155"
LOCATION"C7B28";
"A"
$PN"1"11;
"B"
$PN"2"23;
%"CAP"
"1","(-3300,4325)","1","mstr_discrete","I71";
;
ROOM"DMI"
CDS_LOCATION"C7C2"
$SEC"1"
CDS_SEC"1"
CDS_LIB"mstr_discrete"
BOM_COST"SB"
VOLTAGE"16V"
MATERIAL"X7R"
PACK_TYPE"0402"
TOLERANCE"10%"
VALUE"0.22UF"
PART_NUMBER"A36096-155"
LOCATION"C7C2";
"A"
$PN"1"16;
"B"
$PN"2"24;
%"CAP"
"1","(-3300,3375)","1","mstr_discrete","I72";
;
ROOM"DMI"
CDS_LOCATION"C3M40"
$SEC"1"
CDS_SEC"1"
BOM_COST"SB"
CDS_LIB"mstr_discrete"
VOLTAGE"16V"
PACK_TYPE"0402"
MATERIAL"X7R"
TOLERANCE"10%"
VALUE"0.22UF"
PART_NUMBER"A36096-155"
LOCATION"C3M40";
"A"
$PN"1"12;
"B"
$PN"2"17;
%"CAP"
"1","(-3650,3575)","1","mstr_discrete","I73";
;
ROOM"DMI"
CDS_LOCATION"C3M37"
$SEC"1"
CDS_SEC"1"
BOM_COST"SB"
CDS_LIB"mstr_discrete"
VOLTAGE"16V"
MATERIAL"X7R"
PACK_TYPE"0402"
TOLERANCE"10%"
VALUE"0.22UF"
PART_NUMBER"A36096-155"
LOCATION"C3M37";
"A"
$PN"1"13;
"B"
$PN"2"20;
%"CAP"
"1","(-3300,3775)","1","mstr_discrete","I74";
;
ROOM"DMI"
CDS_LOCATION"C3N9"
$SEC"1"
CDS_SEC"1"
BOM_COST"SB"
CDS_LIB"mstr_discrete"
VOLTAGE"16V"
MATERIAL"X7R"
PACK_TYPE"0402"
TOLERANCE"10%"
VALUE"0.22UF"
PART_NUMBER"A36096-155"
LOCATION"C3N9";
"A"
$PN"1"14;
"B"
$PN"2"18;
%"CAP"
"1","(-3650,3975)","1","mstr_discrete","I75";
;
ROOM"DMI"
CDS_LOCATION"C3N8"
$SEC"1"
CDS_SEC"1"
BOM_COST"SB"
CDS_LIB"mstr_discrete"
VOLTAGE"16V"
MATERIAL"X7R"
PACK_TYPE"0402"
TOLERANCE"10%"
VALUE"0.22UF"
PART_NUMBER"A36096-155"
LOCATION"C3N8";
"A"
$PN"1"15;
"B"
$PN"2"19;
%"CAP"
"1","(750,4325)","1","mstr_discrete","I76";
;
ROOM"DMI"
CDS_LOCATION"C7C3"
$SEC"1"
CDS_SEC"1"
BOM_COST"SB"
CDS_LIB"mstr_discrete"
VOLTAGE"16V"
MATERIAL"X7R"
PACK_TYPE"0402"
TOLERANCE"10%"
VALUE"0.22UF"
PART_NUMBER"A36096-155"
LOCATION"C7C3";
"A"
$PN"1"26;
"B"
$PN"2"37;
%"CAP"
"1","(400,4525)","1","mstr_discrete","I77";
;
ROOM"DMI"
CDS_LOCATION"C7C1"
$SEC"1"
CDS_SEC"1"
BOM_COST"SB"
CDS_LIB"mstr_discrete"
VOLTAGE"16V"
MATERIAL"X7R"
PACK_TYPE"0402"
TOLERANCE"10%"
VALUE"0.22UF"
PART_NUMBER"A36096-155"
LOCATION"C7C1";
"A"
$PN"1"27;
"B"
$PN"2"38;
%"CAP"
"1","(750,4725)","1","mstr_discrete","I78";
;
ROOM"DMI"
CDS_LOCATION"C7B29"
$SEC"1"
CDS_SEC"1"
BOM_COST"SB"
CDS_LIB"mstr_discrete"
VOLTAGE"16V"
MATERIAL"X7R"
PACK_TYPE"0402"
TOLERANCE"10%"
VALUE"0.22UF"
PART_NUMBER"A36096-155"
LOCATION"C7B29";
"A"
$PN"1"28;
"B"
$PN"2"39;
%"CAP"
"1","(400,4925)","1","mstr_discrete","I79";
;
ROOM"DMI"
CDS_LOCATION"C7B26"
$SEC"1"
CDS_SEC"1"
BOM_COST"SB"
CDS_LIB"mstr_discrete"
VOLTAGE"16V"
MATERIAL"X7R"
PACK_TYPE"0402"
TOLERANCE"10%"
VALUE"0.22UF"
PART_NUMBER"A36096-155"
LOCATION"C7B26";
"A"
$PN"1"29;
"B"
$PN"2"40;
%"CAP"
"1","(750,3375)","1","mstr_discrete","I80";
;
ROOM"DMI"
CDS_LOCATION"C3M44"
$SEC"1"
CDS_SEC"1"
BOM_COST"SB"
CDS_LIB"mstr_discrete"
VOLTAGE"16V"
MATERIAL"X7R"
PACK_TYPE"0402"
TOLERANCE"10%"
VALUE"0.22UF"
PART_NUMBER"A36096-155"
LOCATION"C3M44";
"A"
$PN"1"25;
"B"
$PN"2"33;
%"CAP"
"1","(400,3575)","1","mstr_discrete","I81";
;
ROOM"DMI"
CDS_LOCATION"C3M41"
$SEC"1"
CDS_SEC"1"
BOM_COST"SB"
CDS_LIB"mstr_discrete"
VOLTAGE"16V"
MATERIAL"X7R"
PACK_TYPE"0402"
TOLERANCE"10%"
VALUE"0.22UF"
PART_NUMBER"A36096-155"
LOCATION"C3M41";
"A"
$PN"1"30;
"B"
$PN"2"34;
%"CAP"
"1","(750,3775)","1","mstr_discrete","I82";
;
ROOM"DMI"
CDS_LOCATION"C3M45"
$SEC"1"
CDS_SEC"1"
BOM_COST"SB"
CDS_LIB"mstr_discrete"
VOLTAGE"16V"
MATERIAL"X7R"
PACK_TYPE"0402"
TOLERANCE"10%"
VALUE"0.22UF"
PART_NUMBER"A36096-155"
LOCATION"C3M45";
"A"
$PN"1"31;
"B"
$PN"2"35;
%"CAP"
"1","(400,3975)","1","mstr_discrete","I83";
;
ROOM"DMI"
CDS_LOCATION"C3N13"
$SEC"1"
CDS_SEC"1"
BOM_COST"SB"
CDS_LIB"mstr_discrete"
VOLTAGE"16V"
MATERIAL"X7R"
PACK_TYPE"0402"
TOLERANCE"10%"
VALUE"0.22UF"
PART_NUMBER"A36096-155"
LOCATION"C3N13";
"A"
$PN"1"32;
"B"
$PN"2"36;
END.
